(kicad_pcb
	(version 20260206)
	(generator "pcbnew")
	(generator_version "10.0")
	(general
		(thickness 1.6)
		(legacy_teardrops no)
	)
	(paper "A4")
	(title_block
		(title "Wiwynn_Tioga_Pass_MB.brd")
		(comment 1 "Tioga Pass / footprints 1205-1212 of 4770")
	)
	(layers
		(0 "F.Cu" signal "TOP")
		(4 "In1.Cu" signal "L2GND")
		(6 "In2.Cu" signal "L3")
		(8 "In3.Cu" signal "L4GND")
		(10 "In4.Cu" signal "L5")
		(12 "In5.Cu" signal "L6GND")
		(14 "In6.Cu" signal "L7VCC")
		(16 "In7.Cu" signal "L8VCC")
		(18 "In8.Cu" signal "L9GND")
		(20 "In9.Cu" signal "L10")
		(22 "In10.Cu" signal "L11GND")
		(24 "In11.Cu" signal "L12")
		(26 "In12.Cu" signal "L13GND")
		(2 "B.Cu" signal "BOTTOM")
		(9 "F.Adhes" user "F.Adhesive")
		(11 "B.Adhes" user "B.Adhesive")
		(13 "F.Paste" user "Package Geometry/Pastemask Top")
		(15 "B.Paste" user "Package Geometry/Pastemask Bottom")
		(5 "F.SilkS" user "Ref Des/Silkscreen Top")
		(7 "B.SilkS" user "Ref Des/Silkscreen Bottom")
		(1 "F.Mask" user "Board Geometry/Soldermask Top")
		(3 "B.Mask" user "Board Geometry/Soldermask Bottom")
		(17 "Dwgs.User" user "User.Drawings")
		(19 "Cmts.User" user "User.Comments")
		(21 "Eco1.User" user "User.Eco1")
		(23 "Eco2.User" user "User.Eco2")
		(25 "Edge.Cuts" user "Board Geometry/Outline")
		(27 "Margin" user)
		(31 "F.CrtYd" user "Package Geometry/Place Bound Top")
		(29 "B.CrtYd" user "Package Geometry/Place Bound Bottom")
		(35 "F.Fab" user "Ref Des/Assembly Top")
		(33 "B.Fab" user "Ref Des/Assembly Bottom")
	)
	(footprint ""
		(layer "F.Cu")
		(at 177.927 -131.7625)
		(property "Reference" "R4B6"
			(at 0 0 0)
			(layer "F.SilkS")
			(hide yes)
			(effects
				(font
					(size 1.27 1.27)
				)
			)
		)
		(property "Value" ""
			(at 0 0 0)
			(layer "F.Fab")
			(effects
				(font
					(size 1.27 1.27)
				)
			)
		)
		(duplicate_pad_numbers_are_jumpers no)
		(fp_poly
			(pts
				(xy -0.2794 -0.1016) (xy 0.2794 -0.1016) (xy 0.2794 0.9906) (xy -0.2794 0.9906)
			)
			(stroke
				(width 0)
				(type default)
			)
			(fill no)
			(layer "F.CrtYd")
		)
		(fp_line
			(start -0.2794 -0.1016)
			(end -0.2794 0.9906)
			(stroke
				(width 0.1)
				(type default)
			)
			(layer "F.Fab")
		)
		(fp_line
			(start -0.2794 0.9906)
			(end 0.2794 0.9906)
			(stroke
				(width 0.1)
				(type default)
			)
			(layer "F.Fab")
		)
		(fp_line
			(start 0.2794 -0.1016)
			(end -0.2794 -0.1016)
			(stroke
				(width 0.1)
				(type default)
			)
			(layer "F.Fab")
		)
		(fp_line
			(start 0.2794 0.9906)
			(end 0.2794 -0.1016)
			(stroke
				(width 0.1)
				(type default)
			)
			(layer "F.Fab")
		)
		(pad "1" smd rect
			(at 0 0)
			(size 0.508 0.508)
			(layers "F.Cu" "F.Mask" "F.Paste")
			(net "VR_PVPP_KLM_ISET")
		)
		(pad "2" smd rect
			(at 0 0.889)
			(size 0.508 0.508)
			(layers "F.Cu" "F.Mask" "F.Paste")
			(net "AGND_PVPP_KLM")
		)
		(zone
			(layer "F.Cu")
			(hatch none 0.5)
			(connect_pads
				(clearance 0)
			)
			(min_thickness 0.25)
			(keepout
				(tracks allowed)
				(vias not_allowed)
				(pads allowed)
				(copperpour not_allowed)
				(footprints allowed)
			)
			(placement
				(enabled no)
				(sheetname "")
			)
			(fill
				(thermal_gap 0.5)
				(thermal_bridge_width 0.5)
				(island_removal_mode 0)
			)
			(polygon
				(pts
					(xy 177.673 -131.5085) (xy 178.181 -131.5085) (xy 178.181 -131.1275) (xy 177.673 -131.1275)
				)
			)
		)
		(zone
			(layer "F.Cu")
			(hatch none 0.5)
			(connect_pads
				(clearance 0)
			)
			(min_thickness 0.25)
			(keepout
				(tracks not_allowed)
				(vias allowed)
				(pads allowed)
				(copperpour not_allowed)
				(footprints allowed)
			)
			(placement
				(enabled no)
				(sheetname "")
			)
			(fill
				(thermal_gap 0.5)
				(thermal_bridge_width 0.5)
				(island_removal_mode 0)
			)
			(polygon
				(pts
					(xy 177.673 -131.1275) (xy 178.181 -131.1275) (xy 178.181 -131.5085) (xy 177.673 -131.5085)
				)
			)
		)
	)
	(footprint ""
		(layer "F.Cu")
		(at 471.000074 -155.10002 90)
		(property "Reference" "TH9A1"
			(at 3.36931 -4.656074 0)
			(unlocked yes)
			(layer "F.SilkS")
			(effects
				(font
					(size 0.7874 0.5842)
					(thickness 0.1524)
				)
				(justify left)
			)
		)
		(property "Value" ""
			(at 0 0 90)
			(layer "F.Fab")
			(effects
				(font
					(size 1.27 1.27)
				)
			)
		)
		(duplicate_pad_numbers_are_jumpers no)
		(fp_poly
			(pts
				(arc
					(start 3.0226 0.68834)
					(mid 3.042235 0.827855)
					(end 3.099562 0.956564)
				)
				(arc
					(start 3.099562 0.956564)
					(mid 4.012804 3.550073)
					(end 3.042158 6.12267)
				)
				(arc
					(start 3.042158 6.12267)
					(mid 0 7.518589)
					(end -3.042158 6.12267)
				)
				(arc
					(start -3.042158 6.12267)
					(mid -4.012854 3.55061)
					(end -3.100324 0.957326)
				)
				(arc
					(start -3.100324 0.957326)
					(mid -3.042498 0.827518)
					(end -3.0226 0.686816)
				)
				(arc
					(start -3.0226 -0.000254)
					(mid -2.137121 -2.137227)
					(end 0 -3.022346)
				)
				(arc
					(start 0 -3.022346)
					(mid 2.137227 -2.136973)
					(end 3.0226 0.000254)
				)
			)
			(stroke
				(width 0)
				(type default)
			)
			(fill no)
			(layer "F.CrtYd")
		)
		(pad "1" thru_hole custom
			(at 0 0 90)
			(size 2.00667 2.00667)
			(drill 0.3048)
			(layers "*.Cu" "*.Mask")
			(remove_unused_layers no)
			(net "GND")
			(clearance -0.889)
			(options
				(clearance outline)
				(anchor circle)
			)
			(primitives
				(gr_poly
					(pts
						(arc
							(start 3.042158 3.874516)
							(mid 0 5.270435)
							(end -3.042158 3.874516)
						)
						(arc
							(start -3.042158 3.874516)
							(mid -4.012854 1.302456)
							(end -3.100324 -1.290828)
						)
						(arc
							(start -3.100324 -1.290828)
							(mid -3.042498 -1.420636)
							(end -3.0226 -1.561338)
						)
						(arc
							(start -3.0226 -2.248408)
							(mid -2.137121 -4.385381)
							(end 0 -5.2705)
						)
						(arc
							(start 0 -5.2705)
							(mid 2.137227 -4.385127)
							(end 3.0226 -2.2479)
						)
						(arc
							(start 3.0226 -1.55956)
							(mid 3.04227 -1.420177)
							(end 3.099562 -1.29159)
						)
						(arc
							(start 3.099562 -1.29159)
							(mid 4.012804 1.301919)
							(end 3.042158 3.874516)
						)
					)
					(width 0)
					(fill yes)
				)
			)
		)
	)
	(footprint ""
		(layer "F.Cu")
		(at 6.448552 -129.026158)
		(property "Reference" "C12W4"
			(at -0.8382 -0.67818 0)
			(unlocked yes)
			(layer "F.SilkS")
			(effects
				(font
					(size 0.4064 0.254)
					(thickness 0.1524)
				)
				(justify left)
			)
		)
		(property "Value" ""
			(at 0 0 0)
			(layer "F.Fab")
			(effects
				(font
					(size 1.27 1.27)
				)
			)
		)
		(duplicate_pad_numbers_are_jumpers no)
		(fp_poly
			(pts
				(xy 0.3048 -0.1016) (xy 0.3048 0.9906) (xy -0.3048 0.9906) (xy -0.3048 -0.1016)
			)
			(stroke
				(width 0)
				(type default)
			)
			(fill no)
			(layer "F.CrtYd")
		)
		(fp_line
			(start -0.3048 -0.1016)
			(end -0.3048 0.9906)
			(stroke
				(width 0.1)
				(type default)
			)
			(layer "F.Fab")
		)
		(fp_line
			(start -0.3048 0.9906)
			(end 0.3048 0.9906)
			(stroke
				(width 0.1)
				(type default)
			)
			(layer "F.Fab")
		)
		(fp_line
			(start 0.3048 -0.1016)
			(end -0.3048 -0.1016)
			(stroke
				(width 0.1)
				(type default)
			)
			(layer "F.Fab")
		)
		(fp_line
			(start 0.3048 0.9906)
			(end 0.3048 -0.1016)
			(stroke
				(width 0.1)
				(type default)
			)
			(layer "F.Fab")
		)
		(pad "1" smd rect
			(at 0 0)
			(size 0.508 0.508)
			(layers "F.Cu" "F.Mask" "F.Paste")
			(net "VR_PVDDQ_KLM_AIINSEN")
		)
		(pad "2" smd rect
			(at 0 0.889)
			(size 0.508 0.508)
			(layers "F.Cu" "F.Mask" "F.Paste")
			(net "VR_PVDDQ_KLM_VINSEN")
		)
		(zone
			(layer "F.Cu")
			(hatch none 0.5)
			(connect_pads
				(clearance 0)
			)
			(min_thickness 0.25)
			(keepout
				(tracks allowed)
				(vias not_allowed)
				(pads allowed)
				(copperpour not_allowed)
				(footprints allowed)
			)
			(placement
				(enabled no)
				(sheetname "")
			)
			(fill
				(thermal_gap 0.5)
				(thermal_bridge_width 0.5)
				(island_removal_mode 0)
			)
			(polygon
				(pts
					(xy 6.194552 -128.772158) (xy 6.702552 -128.772158) (xy 6.702552 -128.391158) (xy 6.194552 -128.391158)
				)
			)
		)
		(zone
			(layer "F.Cu")
			(hatch none 0.5)
			(connect_pads
				(clearance 0)
			)
			(min_thickness 0.25)
			(keepout
				(tracks not_allowed)
				(vias allowed)
				(pads allowed)
				(copperpour not_allowed)
				(footprints allowed)
			)
			(placement
				(enabled no)
				(sheetname "")
			)
			(fill
				(thermal_gap 0.5)
				(thermal_bridge_width 0.5)
				(island_removal_mode 0)
			)
			(polygon
				(pts
					(xy 6.194552 -128.391158) (xy 6.702552 -128.391158) (xy 6.702552 -128.772158) (xy 6.194552 -128.772158)
				)
			)
		)
	)
	(footprint ""
		(layer "F.Cu")
		(at 105.889806 -68.365116 180)
		(property "Reference" "C2D47"
			(at 0 0 180)
			(layer "F.SilkS")
			(hide yes)
			(effects
				(font
					(size 1.27 1.27)
				)
			)
		)
		(property "Value" ""
			(at 0 0 180)
			(layer "F.Fab")
			(effects
				(font
					(size 1.27 1.27)
				)
			)
		)
		(duplicate_pad_numbers_are_jumpers no)
		(fp_poly
			(pts
				(xy -0.4953 -0.2032) (xy 0.4953 -0.2032) (xy 0.4953 1.6002) (xy -0.4953 1.6002)
			)
			(stroke
				(width 0)
				(type default)
			)
			(fill no)
			(layer "F.CrtYd")
		)
		(fp_line
			(start 0.4953 1.6002)
			(end -0.4953 1.6002)
			(stroke
				(width 0.1)
				(type default)
			)
			(layer "F.Fab")
		)
		(fp_line
			(start 0.4953 -0.2032)
			(end 0.4953 1.6002)
			(stroke
				(width 0.1)
				(type default)
			)
			(layer "F.Fab")
		)
		(fp_line
			(start -0.4953 1.6002)
			(end -0.4953 -0.2032)
			(stroke
				(width 0.1)
				(type default)
			)
			(layer "F.Fab")
		)
		(fp_line
			(start -0.4953 -0.2032)
			(end 0.4953 -0.2032)
			(stroke
				(width 0.1)
				(type default)
			)
			(layer "F.Fab")
		)
		(pad "1" smd rect
			(at 0 0 180)
			(size 0.762 0.889)
			(layers "F.Cu" "F.Mask" "F.Paste")
			(net "PVDDQ_GHJ")
		)
		(pad "2" smd rect
			(at 0 1.397 180)
			(size 0.762 0.889)
			(layers "F.Cu" "F.Mask" "F.Paste")
			(net "GND")
		)
		(zone
			(layer "F.Cu")
			(hatch none 0.5)
			(connect_pads
				(clearance 0)
			)
			(min_thickness 0.25)
			(keepout
				(tracks not_allowed)
				(vias allowed)
				(pads allowed)
				(copperpour not_allowed)
				(footprints allowed)
			)
			(placement
				(enabled no)
				(sheetname "")
			)
			(fill
				(thermal_gap 0.5)
				(thermal_bridge_width 0.5)
				(island_removal_mode 0)
			)
			(polygon
				(pts
					(xy 106.270806 -68.809616) (xy 105.508806 -68.809616) (xy 105.508806 -69.317616) (xy 106.270806 -69.317616)
				)
			)
		)
	)
	(footprint ""
		(layer "F.Cu")
		(at 277.241 -69.977)
		(property "Reference" "R6D15"
			(at 0 0 0)
			(layer "F.SilkS")
			(hide yes)
			(effects
				(font
					(size 1.27 1.27)
				)
			)
		)
		(property "Value" ""
			(at 0 0 0)
			(layer "F.Fab")
			(effects
				(font
					(size 1.27 1.27)
				)
			)
		)
		(duplicate_pad_numbers_are_jumpers no)
		(fp_poly
			(pts
				(xy -0.2794 -0.1016) (xy 0.2794 -0.1016) (xy 0.2794 0.9906) (xy -0.2794 0.9906)
			)
			(stroke
				(width 0)
				(type default)
			)
			(fill no)
			(layer "F.CrtYd")
		)
		(fp_line
			(start -0.2794 -0.1016)
			(end -0.2794 0.9906)
			(stroke
				(width 0.1)
				(type default)
			)
			(layer "F.Fab")
		)
		(fp_line
			(start -0.2794 0.9906)
			(end 0.2794 0.9906)
			(stroke
				(width 0.1)
				(type default)
			)
			(layer "F.Fab")
		)
		(fp_line
			(start 0.2794 -0.1016)
			(end -0.2794 -0.1016)
			(stroke
				(width 0.1)
				(type default)
			)
			(layer "F.Fab")
		)
		(fp_line
			(start 0.2794 0.9906)
			(end 0.2794 -0.1016)
			(stroke
				(width 0.1)
				(type default)
			)
			(layer "F.Fab")
		)
		(pad "1" smd rect
			(at 0 0)
			(size 0.508 0.508)
			(layers "F.Cu" "F.Mask" "F.Paste")
			(net "PVCCIO_CPU0")
		)
		(pad "2" smd rect
			(at 0 0.889)
			(size 0.508 0.508)
			(layers "F.Cu" "F.Mask" "F.Paste")
			(net "PU_CPU0_SOCKET_ID_0")
		)
		(zone
			(layer "F.Cu")
			(hatch none 0.5)
			(connect_pads
				(clearance 0)
			)
			(min_thickness 0.25)
			(keepout
				(tracks allowed)
				(vias not_allowed)
				(pads allowed)
				(copperpour not_allowed)
				(footprints allowed)
			)
			(placement
				(enabled no)
				(sheetname "")
			)
			(fill
				(thermal_gap 0.5)
				(thermal_bridge_width 0.5)
				(island_removal_mode 0)
			)
			(polygon
				(pts
					(xy 276.987 -69.723) (xy 277.495 -69.723) (xy 277.495 -69.342) (xy 276.987 -69.342)
				)
			)
		)
		(zone
			(layer "F.Cu")
			(hatch none 0.5)
			(connect_pads
				(clearance 0)
			)
			(min_thickness 0.25)
			(keepout
				(tracks not_allowed)
				(vias allowed)
				(pads allowed)
				(copperpour not_allowed)
				(footprints allowed)
			)
			(placement
				(enabled no)
				(sheetname "")
			)
			(fill
				(thermal_gap 0.5)
				(thermal_bridge_width 0.5)
				(island_removal_mode 0)
			)
			(polygon
				(pts
					(xy 276.987 -69.342) (xy 277.495 -69.342) (xy 277.495 -69.723) (xy 276.987 -69.723)
				)
			)
		)
	)
	(footprint ""
		(layer "F.Cu")
		(at 411.099 -127.5588 90)
		(property "Reference" "C8B11"
			(at 0 0 90)
			(layer "F.SilkS")
			(hide yes)
			(effects
				(font
					(size 1.27 1.27)
				)
			)
		)
		(property "Value" ""
			(at 0 0 90)
			(layer "F.Fab")
			(effects
				(font
					(size 1.27 1.27)
				)
			)
		)
		(duplicate_pad_numbers_are_jumpers no)
		(fp_poly
			(pts
				(xy -0.4953 -0.2032) (xy 0.4953 -0.2032) (xy 0.4953 1.6002) (xy -0.4953 1.6002)
			)
			(stroke
				(width 0)
				(type default)
			)
			(fill no)
			(layer "F.CrtYd")
		)
		(fp_line
			(start 0.4953 -0.2032)
			(end 0.4953 1.6002)
			(stroke
				(width 0.1)
				(type default)
			)
			(layer "F.Fab")
		)
		(fp_line
			(start -0.4953 -0.2032)
			(end 0.4953 -0.2032)
			(stroke
				(width 0.1)
				(type default)
			)
			(layer "F.Fab")
		)
		(fp_line
			(start 0.4953 1.6002)
			(end -0.4953 1.6002)
			(stroke
				(width 0.1)
				(type default)
			)
			(layer "F.Fab")
		)
		(fp_line
			(start -0.4953 1.6002)
			(end -0.4953 -0.2032)
			(stroke
				(width 0.1)
				(type default)
			)
			(layer "F.Fab")
		)
		(pad "1" smd rect
			(at 0 0 90)
			(size 0.762 0.889)
			(layers "F.Cu" "F.Mask" "F.Paste")
			(net "P1V05_PCH_STBY")
		)
		(pad "2" smd rect
			(at 0 1.397 90)
			(size 0.762 0.889)
			(layers "F.Cu" "F.Mask" "F.Paste")
			(net "GND")
		)
		(zone
			(layer "F.Cu")
			(hatch none 0.5)
			(connect_pads
				(clearance 0)
			)
			(min_thickness 0.25)
			(keepout
				(tracks not_allowed)
				(vias allowed)
				(pads allowed)
				(copperpour not_allowed)
				(footprints allowed)
			)
			(placement
				(enabled no)
				(sheetname "")
			)
			(fill
				(thermal_gap 0.5)
				(thermal_bridge_width 0.5)
				(island_removal_mode 0)
			)
			(polygon
				(pts
					(xy 411.5435 -127.1778) (xy 411.5435 -127.9398) (xy 412.0515 -127.9398) (xy 412.0515 -127.1778)
				)
			)
		)
	)
	(footprint ""
		(layer "F.Cu")
		(at 477.139 -36.6395 180)
		(property "Reference" "R8G25"
			(at 0 0 180)
			(layer "F.SilkS")
			(hide yes)
			(effects
				(font
					(size 1.27 1.27)
				)
			)
		)
		(property "Value" ""
			(at 0 0 180)
			(layer "F.Fab")
			(effects
				(font
					(size 1.27 1.27)
				)
			)
		)
		(duplicate_pad_numbers_are_jumpers no)
		(fp_poly
			(pts
				(xy -0.2794 -0.1016) (xy 0.2794 -0.1016) (xy 0.2794 0.9906) (xy -0.2794 0.9906)
			)
			(stroke
				(width 0)
				(type default)
			)
			(fill no)
			(layer "F.CrtYd")
		)
		(fp_line
			(start 0.2794 0.9906)
			(end 0.2794 -0.1016)
			(stroke
				(width 0.1)
				(type default)
			)
			(layer "F.Fab")
		)
		(fp_line
			(start 0.2794 -0.1016)
			(end -0.2794 -0.1016)
			(stroke
				(width 0.1)
				(type default)
			)
			(layer "F.Fab")
		)
		(fp_line
			(start -0.2794 0.9906)
			(end 0.2794 0.9906)
			(stroke
				(width 0.1)
				(type default)
			)
			(layer "F.Fab")
		)
		(fp_line
			(start -0.2794 -0.1016)
			(end -0.2794 0.9906)
			(stroke
				(width 0.1)
				(type default)
			)
			(layer "F.Fab")
		)
		(pad "1" smd rect
			(at 0 0 180)
			(size 0.508 0.508)
			(layers "F.Cu" "F.Mask" "F.Paste")
			(net "CLK_50M_CKMNG_SPRVLLE_R")
		)
		(pad "2" smd rect
			(at 0 0.889 180)
			(size 0.508 0.508)
			(layers "F.Cu" "F.Mask" "F.Paste")
			(net "CLK_50M_CKMNG_SPRVLLE")
		)
		(zone
			(layer "F.Cu")
			(hatch none 0.5)
			(connect_pads
				(clearance 0)
			)
			(min_thickness 0.25)
			(keepout
				(tracks not_allowed)
				(vias allowed)
				(pads allowed)
				(copperpour not_allowed)
				(footprints allowed)
			)
			(placement
				(enabled no)
				(sheetname "")
			)
			(fill
				(thermal_gap 0.5)
				(thermal_bridge_width 0.5)
				(island_removal_mode 0)
			)
			(polygon
				(pts
					(xy 477.393 -37.2745) (xy 476.885 -37.2745) (xy 476.885 -36.8935) (xy 477.393 -36.8935)
				)
			)
		)
		(zone
			(layer "F.Cu")
			(hatch none 0.5)
			(connect_pads
				(clearance 0)
			)
			(min_thickness 0.25)
			(keepout
				(tracks allowed)
				(vias not_allowed)
				(pads allowed)
				(copperpour not_allowed)
				(footprints allowed)
			)
			(placement
				(enabled no)
				(sheetname "")
			)
			(fill
				(thermal_gap 0.5)
				(thermal_bridge_width 0.5)
				(island_removal_mode 0)
			)
			(polygon
				(pts
					(xy 477.393 -36.8935) (xy 476.885 -36.8935) (xy 476.885 -37.2745) (xy 477.393 -37.2745)
				)
			)
		)
	)
	(footprint ""
		(layer "F.Cu")
		(at 350.376236 4.434332 90)
		(property "Reference" "C7G37"
			(at 0 0 90)
			(layer "F.SilkS")
			(hide yes)
			(effects
				(font
					(size 1.27 1.27)
				)
			)
		)
		(property "Value" ""
			(at 0 0 90)
			(layer "F.Fab")
			(effects
				(font
					(size 1.27 1.27)
				)
			)
		)
		(duplicate_pad_numbers_are_jumpers no)
		(fp_poly
			(pts
				(xy 0.3048 -0.1016) (xy 0.3048 0.9906) (xy -0.3048 0.9906) (xy -0.3048 -0.1016)
			)
			(stroke
				(width 0)
				(type default)
			)
			(fill no)
			(layer "F.CrtYd")
		)
		(fp_line
			(start 0.3048 -0.1016)
			(end -0.3048 -0.1016)
			(stroke
				(width 0.1)
				(type default)
			)
			(layer "F.Fab")
		)
		(fp_line
			(start -0.3048 -0.1016)
			(end -0.3048 0.9906)
			(stroke
				(width 0.1)
				(type default)
			)
			(layer "F.Fab")
		)
		(fp_line
			(start 0.3048 0.9906)
			(end 0.3048 -0.1016)
			(stroke
				(width 0.1)
				(type default)
			)
			(layer "F.Fab")
		)
		(fp_line
			(start -0.3048 0.9906)
			(end 0.3048 0.9906)
			(stroke
				(width 0.1)
				(type default)
			)
			(layer "F.Fab")
		)
		(pad "1" smd rect
			(at 0 0 90)
			(size 0.508 0.508)
			(layers "F.Cu" "F.Mask" "F.Paste")
			(net "VR_FET_SW_P12V_STBY_PVDDQ_ABC")
		)
		(pad "2" smd rect
			(at 0 0.889 90)
			(size 0.508 0.508)
			(layers "F.Cu" "F.Mask" "F.Paste")
			(net "GND")
		)
		(zone
			(layer "F.Cu")
			(hatch none 0.5)
			(connect_pads
				(clearance 0)
			)
			(min_thickness 0.25)
			(keepout
				(tracks allowed)
				(vias not_allowed)
				(pads allowed)
				(copperpour not_allowed)
				(footprints allowed)
			)
			(placement
				(enabled no)
				(sheetname "")
			)
			(fill
				(thermal_gap 0.5)
				(thermal_bridge_width 0.5)
				(island_removal_mode 0)
			)
			(polygon
				(pts
					(xy 350.630236 4.688332) (xy 350.630236 4.180332) (xy 351.011236 4.180332) (xy 351.011236 4.688332)
				)
			)
		)
		(zone
			(layer "F.Cu")
			(hatch none 0.5)
			(connect_pads
				(clearance 0)
			)
			(min_thickness 0.25)
			(keepout
				(tracks not_allowed)
				(vias allowed)
				(pads allowed)
				(copperpour not_allowed)
				(footprints allowed)
			)
			(placement
				(enabled no)
				(sheetname "")
			)
			(fill
				(thermal_gap 0.5)
				(thermal_bridge_width 0.5)
				(island_removal_mode 0)
			)
			(polygon
				(pts
					(xy 351.011236 4.688332) (xy 351.011236 4.180332) (xy 350.630236 4.180332) (xy 350.630236 4.688332)
				)
			)
		)
	)
)
